(kicad_pcb
	(version 20241229)
	(generator "pcbnew")
	(generator_version "9.0")
	(general
		(thickness 1.6642)
		(legacy_teardrops no)
	)
	(paper "A3")
	(title_block
		(title "PolarFire SoM")
		(date "2025-07-22")
		(rev "1.1.4")
		(company "Antmicro Ltd")
		(comment 1 "www.antmicro.com")
		(comment 9 "footprints 326-329 of 470")
	)
	(layers
		(0 "F.Cu" mixed)
		(4 "In1.Cu" power)
		(6 "In2.Cu" signal)
		(8 "In3.Cu" power)
		(10 "In4.Cu" signal)
		(12 "In5.Cu" power)
		(14 "In6.Cu" power)
		(16 "In7.Cu" signal)
		(18 "In8.Cu" power)
		(20 "In9.Cu" signal)
		(22 "In10.Cu" power)
		(24 "In11.Cu" signal)
		(26 "In12.Cu" signal)
		(2 "B.Cu" mixed)
		(9 "F.Adhes" user "F.Adhesive")
		(11 "B.Adhes" user "B.Adhesive")
		(13 "F.Paste" user)
		(15 "B.Paste" user)
		(5 "F.SilkS" user "F.Silkscreen")
		(7 "B.SilkS" user "B.Silkscreen")
		(1 "F.Mask" user)
		(3 "B.Mask" user)
		(17 "Dwgs.User" user "User.Drawings")
		(19 "Cmts.User" user "User.Comments")
		(21 "Eco1.User" user "User.Eco1")
		(23 "Eco2.User" user "User.Eco2")
		(25 "Edge.Cuts" user)
		(27 "Margin" user)
		(31 "F.CrtYd" user "F.Courtyard")
		(29 "B.CrtYd" user "B.Courtyard")
		(35 "F.Fab" user)
		(33 "B.Fab" user)
	)
	(footprint "antmicro-footprints:C_0402_1005Metric"
		(layer "B.Cu")
		(at 213.861 118.754 180)
		(descr "Capacitor SMD 0402")
		(tags "capacitor SMD 0402")
		(property "Reference" "C190"
			(at 24.711 -18.021 0)
			(layer "B.SilkS")
			(effects
				(font
					(size 0.7 0.7)
					(thickness 0.15)
				)
				(justify left bottom mirror)
			)
		)
		(property "Value" "C_100n_0402"
			(at -1.022927 -2.155213 0)
			(layer "B.Fab")
			(hide yes)
			(effects
				(font
					(size 0.7 0.7)
					(thickness 0.15)
				)
				(justify left bottom mirror)
			)
		)
		(property "Datasheet" "https://www.murata.com/products/productdetail?partno=GRM155R61H104KE14%23"
			(at 0 0 180)
			(layer "F.Fab")
			(hide yes)
			(effects
				(font
					(size 1.27 1.27)
					(thickness 0.15)
				)
			)
		)
		(property "Description" "SMD Multilayer Ceramic Capacitor, 0.1 µF, 50 V, 0402 [1005 Metric], ± 10%, X5R, GRM Series"
			(at 0 0 180)
			(layer "F.Fab")
			(hide yes)
			(effects
				(font
					(size 1.27 1.27)
					(thickness 0.15)
				)
			)
		)
		(property "Author" "Antmicro"
			(at 427.722 237.508 0)
			(layer "B.Fab")
			(hide yes)
			(effects
				(font
					(size 1 1)
					(thickness 0.15)
				)
				(justify mirror)
			)
		)
		(property "Dielectric" "X5R"
			(at 427.722 237.508 0)
			(layer "B.Fab")
			(hide yes)
			(effects
				(font
					(size 1 1)
					(thickness 0.15)
				)
				(justify mirror)
			)
		)
		(property "License" "Apache-2.0"
			(at 427.722 237.508 0)
			(layer "B.Fab")
			(hide yes)
			(effects
				(font
					(size 1 1)
					(thickness 0.15)
				)
				(justify mirror)
			)
		)
		(property "MPN" "GRM155R61H104KE14D"
			(at 427.722 237.508 0)
			(layer "B.Fab")
			(hide yes)
			(effects
				(font
					(size 1 1)
					(thickness 0.15)
				)
				(justify mirror)
			)
		)
		(property "Manufacturer" "Murata"
			(at 427.722 237.508 0)
			(layer "B.Fab")
			(hide yes)
			(effects
				(font
					(size 1 1)
					(thickness 0.15)
				)
				(justify mirror)
			)
		)
		(property "Public" ""
			(at 427.722 237.508 0)
			(layer "B.Fab")
			(hide yes)
			(effects
				(font
					(size 1 1)
					(thickness 0.15)
				)
				(justify mirror)
			)
		)
		(property "Val" "100n"
			(at 427.722 237.508 0)
			(layer "B.Fab")
			(hide yes)
			(effects
				(font
					(size 1 1)
					(thickness 0.15)
				)
				(justify mirror)
			)
		)
		(property "Voltage" "50V"
			(at 427.722 237.508 0)
			(layer "B.Fab")
			(hide yes)
			(effects
				(font
					(size 1 1)
					(thickness 0.15)
				)
				(justify mirror)
			)
		)
		(sheetname "/Ethernet/")
		(sheetfile "ethernet.kicad_sch")
		(attr smd)
		(fp_rect
			(start -0.925 0.47)
			(end 0.925 -0.47)
			(stroke
				(width 0.05)
				(type default)
			)
			(fill no)
			(layer "B.CrtYd")
		)
		(fp_line
			(start 0.504 0.25)
			(end 0.504 -0.248)
			(stroke
				(width 0.15)
				(type solid)
			)
			(layer "B.Fab")
		)
		(fp_line
			(start 0.504 -0.248)
			(end -0.494 -0.248)
			(stroke
				(width 0.15)
				(type solid)
			)
			(layer "B.Fab")
		)
		(fp_line
			(start -0.494 0.25)
			(end 0.504 0.25)
			(stroke
				(width 0.15)
				(type solid)
			)
			(layer "B.Fab")
		)
		(fp_line
			(start -0.494 -0.248)
			(end -0.494 0.25)
			(stroke
				(width 0.15)
				(type solid)
			)
			(layer "B.Fab")
		)
		(fp_text user "Author: Antmicro"
			(at -0.939 -3.399 0)
			(layer "B.Fab")
			(effects
				(font
					(size 0.7 0.7)
					(thickness 0.15)
				)
				(justify left bottom mirror)
			)
		)
		(fp_text user "License: Apache-2.0"
			(at -0.939 -5.799 0)
			(layer "B.Fab")
			(effects
				(font
					(size 0.7 0.7)
					(thickness 0.15)
				)
				(justify left bottom mirror)
			)
		)
		(fp_text user "${REFERENCE}"
			(at -0.939 -4.599 0)
			(layer "B.Fab")
			(effects
				(font
					(size 0.7 0.7)
					(thickness 0.15)
				)
				(justify left bottom mirror)
			)
		)
		(pad "1" smd roundrect
			(at -0.48 0 180)
			(size 0.59 0.64)
			(layers "B.Cu" "B.Mask" "B.Paste")
			(roundrect_rratio 0.25)
			(net 417 "GND")
			(pintype "passive")
		)
		(pad "2" smd roundrect
			(at 0.48 0 180)
			(size 0.59 0.64)
			(layers "B.Cu" "B.Mask" "B.Paste")
			(roundrect_rratio 0.25)
			(net 50 "+3V3")
			(pintype "passive")
		)
	)
	(footprint "antmicro-footprints:C_0402_1005Metric"
		(layer "B.Cu")
		(at 211.965 144.65 90)
		(descr "Capacitor SMD 0402")
		(tags "capacitor SMD 0402")
		(property "Reference" "C183"
			(at 4.925 -0.415 270)
			(layer "B.SilkS")
			(effects
				(font
					(size 0.7 0.7)
					(thickness 0.15)
				)
				(justify left bottom mirror)
			)
		)
		(property "Value" "C_100n_0402"
			(at -1.022927 -2.155213 270)
			(layer "B.Fab")
			(hide yes)
			(effects
				(font
					(size 0.7 0.7)
					(thickness 0.15)
				)
				(justify left bottom mirror)
			)
		)
		(property "Datasheet" "https://www.murata.com/products/productdetail?partno=GRM155R61H104KE14%23"
			(at 0 0 90)
			(layer "F.Fab")
			(hide yes)
			(effects
				(font
					(size 1.27 1.27)
					(thickness 0.15)
				)
			)
		)
		(property "Description" "SMD Multilayer Ceramic Capacitor, 0.1 µF, 50 V, 0402 [1005 Metric], ± 10%, X5R, GRM Series"
			(at 0 0 90)
			(layer "F.Fab")
			(hide yes)
			(effects
				(font
					(size 1.27 1.27)
					(thickness 0.15)
				)
			)
		)
		(property "Author" "Antmicro"
			(at 356.615 -67.315 0)
			(layer "B.Fab")
			(hide yes)
			(effects
				(font
					(size 1 1)
					(thickness 0.15)
				)
				(justify mirror)
			)
		)
		(property "Dielectric" "X5R"
			(at 356.615 -67.315 0)
			(layer "B.Fab")
			(hide yes)
			(effects
				(font
					(size 1 1)
					(thickness 0.15)
				)
				(justify mirror)
			)
		)
		(property "License" "Apache-2.0"
			(at 356.615 -67.315 0)
			(layer "B.Fab")
			(hide yes)
			(effects
				(font
					(size 1 1)
					(thickness 0.15)
				)
				(justify mirror)
			)
		)
		(property "MPN" "GRM155R61H104KE14D"
			(at 356.615 -67.315 0)
			(layer "B.Fab")
			(hide yes)
			(effects
				(font
					(size 1 1)
					(thickness 0.15)
				)
				(justify mirror)
			)
		)
		(property "Manufacturer" "Murata"
			(at 356.615 -67.315 0)
			(layer "B.Fab")
			(hide yes)
			(effects
				(font
					(size 1 1)
					(thickness 0.15)
				)
				(justify mirror)
			)
		)
		(property "Public" ""
			(at 356.615 -67.315 0)
			(layer "B.Fab")
			(hide yes)
			(effects
				(font
					(size 1 1)
					(thickness 0.15)
				)
				(justify mirror)
			)
		)
		(property "Val" "100n"
			(at 356.615 -67.315 0)
			(layer "B.Fab")
			(hide yes)
			(effects
				(font
					(size 1 1)
					(thickness 0.15)
				)
				(justify mirror)
			)
		)
		(property "Voltage" "50V"
			(at 356.615 -67.315 0)
			(layer "B.Fab")
			(hide yes)
			(effects
				(font
					(size 1 1)
					(thickness 0.15)
				)
				(justify mirror)
			)
		)
		(sheetname "/USB/")
		(sheetfile "usb.kicad_sch")
		(attr smd)
		(fp_rect
			(start -0.925 0.47)
			(end 0.925 -0.47)
			(stroke
				(width 0.05)
				(type default)
			)
			(fill no)
			(layer "B.CrtYd")
		)
		(fp_line
			(start 0.504 -0.248)
			(end -0.494 -0.248)
			(stroke
				(width 0.15)
				(type solid)
			)
			(layer "B.Fab")
		)
		(fp_line
			(start -0.494 -0.248)
			(end -0.494 0.25)
			(stroke
				(width 0.15)
				(type solid)
			)
			(layer "B.Fab")
		)
		(fp_line
			(start 0.504 0.25)
			(end 0.504 -0.248)
			(stroke
				(width 0.15)
				(type solid)
			)
			(layer "B.Fab")
		)
		(fp_line
			(start -0.494 0.25)
			(end 0.504 0.25)
			(stroke
				(width 0.15)
				(type solid)
			)
			(layer "B.Fab")
		)
		(fp_text user "${REFERENCE}"
			(at -0.939 -4.599 270)
			(layer "B.Fab")
			(effects
				(font
					(size 0.7 0.7)
					(thickness 0.15)
				)
				(justify left bottom mirror)
			)
		)
		(fp_text user "Author: Antmicro"
			(at -0.939 -3.399 270)
			(layer "B.Fab")
			(effects
				(font
					(size 0.7 0.7)
					(thickness 0.15)
				)
				(justify left bottom mirror)
			)
		)
		(fp_text user "License: Apache-2.0"
			(at -0.939 -5.799 270)
			(layer "B.Fab")
			(effects
				(font
					(size 0.7 0.7)
					(thickness 0.15)
				)
				(justify left bottom mirror)
			)
		)
		(pad "1" smd roundrect
			(at -0.48 0 90)
			(size 0.59 0.64)
			(layers "B.Cu" "B.Mask" "B.Paste")
			(roundrect_rratio 0.25)
			(net 417 "GND")
			(pintype "passive")
		)
		(pad "2" smd roundrect
			(at 0.48 0 90)
			(size 0.59 0.64)
			(layers "B.Cu" "B.Mask" "B.Paste")
			(roundrect_rratio 0.25)
			(net 50 "+3V3")
			(pintype "passive")
		)
	)
	(footprint "antmicro-footprints:R_0402_1005Metric"
		(layer "B.Cu")
		(at 226.075 147.82 90)
		(descr "Resistor SMD 0402")
		(tags "resistor SMD 0402")
		(property "Reference" "R130"
			(at 0.92 2.405 270)
			(layer "B.SilkS")
			(effects
				(font
					(size 0.7 0.7)
					(thickness 0.15)
				)
				(justify left bottom mirror)
			)
		)
		(property "Value" "R_0R_0402"
			(at -1.011843 -1.772047 270)
			(layer "B.Fab")
			(hide yes)
			(effects
				(font
					(size 0.7 0.7)
					(thickness 0.15)
				)
				(justify left bottom mirror)
			)
		)
		(property "Datasheet" "https://industrial.panasonic.com/cdbs/www-data/pdf/RDA0000/AOA0000C301.pdf"
			(at 0 0 90)
			(layer "F.Fab")
			(hide yes)
			(effects
				(font
					(size 1.27 1.27)
					(thickness 0.15)
				)
			)
		)
		(property "Description" "SMD Chip Resistor, Jumper, 0 ohm, 100 mW, 0402 [1005 Metric], Thick Film, General Purpose"
			(at 0 0 90)
			(layer "F.Fab")
			(hide yes)
			(effects
				(font
					(size 1.27 1.27)
					(thickness 0.15)
				)
			)
		)
		(property "Author" "Antmicro"
			(at 373.895 -78.255 0)
			(layer "B.Fab")
			(hide yes)
			(effects
				(font
					(size 1 1)
					(thickness 0.15)
				)
				(justify mirror)
			)
		)
		(property "Current" "1A"
			(at 373.895 -78.255 0)
			(layer "B.Fab")
			(hide yes)
			(effects
				(font
					(size 1 1)
					(thickness 0.15)
				)
				(justify mirror)
			)
		)
		(property "License" "Apache-2.0"
			(at 373.895 -78.255 0)
			(layer "B.Fab")
			(hide yes)
			(effects
				(font
					(size 1 1)
					(thickness 0.15)
				)
				(justify mirror)
			)
		)
		(property "MPN" "ERJ2GE0R00X"
			(at 373.895 -78.255 0)
			(layer "B.Fab")
			(hide yes)
			(effects
				(font
					(size 1 1)
					(thickness 0.15)
				)
				(justify mirror)
			)
		)
		(property "Manufacturer" "Panasonic"
			(at 373.895 -78.255 0)
			(layer "B.Fab")
			(hide yes)
			(effects
				(font
					(size 1 1)
					(thickness 0.15)
				)
				(justify mirror)
			)
		)
		(property "Public" ""
			(at 373.895 -78.255 0)
			(layer "B.Fab")
			(hide yes)
			(effects
				(font
					(size 1 1)
					(thickness 0.15)
				)
				(justify mirror)
			)
		)
		(property "Tolerance" "~"
			(at 373.895 -78.255 0)
			(layer "B.Fab")
			(hide yes)
			(effects
				(font
					(size 1 1)
					(thickness 0.15)
				)
				(justify mirror)
			)
		)
		(property "Val" "0R"
			(at 373.895 -78.255 0)
			(layer "B.Fab")
			(hide yes)
			(effects
				(font
					(size 1 1)
					(thickness 0.15)
				)
				(justify mirror)
			)
		)
		(sheetname "/FPGA MSSIO/")
		(sheetfile "fpga-mssio.kicad_sch")
		(attr smd)
		(fp_rect
			(start -0.925 0.47)
			(end 0.925 -0.47)
			(stroke
				(width 0.05)
				(type default)
			)
			(fill no)
			(layer "B.CrtYd")
		)
		(fp_rect
			(start -0.5 0.25)
			(end 0.5 -0.25)
			(stroke
				(width 0.15)
				(type solid)
			)
			(fill no)
			(layer "B.Fab")
		)
		(fp_text user "${REFERENCE}"
			(at -0.95 -3.168 270)
			(layer "B.Fab")
			(effects
				(font
					(size 0.7 0.7)
					(thickness 0.15)
				)
				(justify left bottom mirror)
			)
		)
		(fp_text user "License: Apache-2.0"
			(at -0.95 -5.169 270)
			(layer "B.Fab")
			(effects
				(font
					(size 0.7 0.7)
					(thickness 0.15)
				)
				(justify left bottom mirror)
			)
		)
		(fp_text user "Author: Antmicro"
			(at -0.95 -4.169 270)
			(layer "B.Fab")
			(effects
				(font
					(size 0.7 0.7)
					(thickness 0.15)
				)
				(justify left bottom mirror)
			)
		)
		(pad "1" smd roundrect
			(at -0.48 0 90)
			(size 0.59 0.64)
			(layers "B.Cu" "B.Mask" "B.Paste")
			(roundrect_rratio 0.25)
			(net 295 "Net-(U1C-MSSIO36B2)")
			(pintype "passive")
		)
		(pad "2" smd roundrect
			(at 0.48 0 90)
			(size 0.59 0.64)
			(layers "B.Cu" "B.Mask" "B.Paste")
			(roundrect_rratio 0.25)
			(net 194 "/FPGA MSSIO/BT_UART_RX")
			(pintype "passive")
		)
	)
	(footprint "antmicro-footprints:C_0402_1005Metric"
		(layer "B.Cu")
		(at 212.1925 133.697)
		(descr "Capacitor SMD 0402")
		(tags "capacitor SMD 0402")
		(property "Reference" "C77"
			(at -0.4175 2.528 0)
			(layer "B.SilkS")
			(effects
				(font
					(size 0.7 0.7)
					(thickness 0.15)
				)
				(justify right bottom mirror)
			)
		)
		(property "Value" "C_100n_0402"
			(at -1.022927 -2.155213 0)
			(layer "B.Fab")
			(hide yes)
			(effects
				(font
					(size 0.7 0.7)
					(thickness 0.15)
				)
				(justify right bottom mirror)
			)
		)
		(property "Datasheet" "https://www.murata.com/products/productdetail?partno=GRM155R61H104KE14%23"
			(at 0 0 0)
			(layer "F.Fab")
			(hide yes)
			(effects
				(font
					(size 1.27 1.27)
					(thickness 0.15)
				)
			)
		)
		(property "Description" "SMD Multilayer Ceramic Capacitor, 0.1 µF, 50 V, 0402 [1005 Metric], ± 10%, X5R, GRM Series"
			(at 0 0 0)
			(layer "F.Fab")
			(hide yes)
			(effects
				(font
					(size 1.27 1.27)
					(thickness 0.15)
				)
			)
		)
		(property "Author" "Antmicro"
			(at 0 0 0)
			(layer "B.Fab")
			(hide yes)
			(effects
				(font
					(size 1 1)
					(thickness 0.15)
				)
				(justify mirror)
			)
		)
		(property "Dielectric" "X5R"
			(at 0 0 0)
			(layer "B.Fab")
			(hide yes)
			(effects
				(font
					(size 1 1)
					(thickness 0.15)
				)
				(justify mirror)
			)
		)
		(property "License" "Apache-2.0"
			(at 0 0 0)
			(layer "B.Fab")
			(hide yes)
			(effects
				(font
					(size 1 1)
					(thickness 0.15)
				)
				(justify mirror)
			)
		)
		(property "MPN" "GRM155R61H104KE14D"
			(at 0 0 0)
			(layer "B.Fab")
			(hide yes)
			(effects
				(font
					(size 1 1)
					(thickness 0.15)
				)
				(justify mirror)
			)
		)
		(property "Manufacturer" "Murata"
			(at 0 0 0)
			(layer "B.Fab")
			(hide yes)
			(effects
				(font
					(size 1 1)
					(thickness 0.15)
				)
				(justify mirror)
			)
		)
		(property "Public" ""
			(at 0 0 0)
			(layer "B.Fab")
			(hide yes)
			(effects
				(font
					(size 1 1)
					(thickness 0.15)
				)
				(justify mirror)
			)
		)
		(property "Val" "100n"
			(at 0 0 0)
			(layer "B.Fab")
			(hide yes)
			(effects
				(font
					(size 1 1)
					(thickness 0.15)
				)
				(justify mirror)
			)
		)
		(property "Voltage" "50V"
			(at 0 0 0)
			(layer "B.Fab")
			(hide yes)
			(effects
				(font
					(size 1 1)
					(thickness 0.15)
				)
				(justify mirror)
			)
		)
		(sheetname "/Memory/")
		(sheetfile "memory.kicad_sch")
		(attr smd)
		(fp_rect
			(start -0.925 0.47)
			(end 0.925 -0.47)
			(stroke
				(width 0.05)
				(type default)
			)
			(fill no)
			(layer "B.CrtYd")
		)
		(fp_line
			(start -0.494 -0.248)
			(end -0.494 0.25)
			(stroke
				(width 0.15)
				(type solid)
			)
			(layer "B.Fab")
		)
		(fp_line
			(start -0.494 0.25)
			(end 0.504 0.25)
			(stroke
				(width 0.15)
				(type solid)
			)
			(layer "B.Fab")
		)
		(fp_line
			(start 0.504 -0.248)
			(end -0.494 -0.248)
			(stroke
				(width 0.15)
				(type solid)
			)
			(layer "B.Fab")
		)
		(fp_line
			(start 0.504 0.25)
			(end 0.504 -0.248)
			(stroke
				(width 0.15)
				(type solid)
			)
			(layer "B.Fab")
		)
		(fp_text user "License: Apache-2.0"
			(at -0.939 -5.799 180)
			(layer "B.Fab")
			(effects
				(font
					(size 0.7 0.7)
					(thickness 0.15)
				)
				(justify left bottom mirror)
			)
		)
		(fp_text user "Author: Antmicro"
			(at -0.939 -3.399 180)
			(layer "B.Fab")
			(effects
				(font
					(size 0.7 0.7)
					(thickness 0.15)
				)
				(justify left bottom mirror)
			)
		)
		(fp_text user "${REFERENCE}"
			(at -0.939 -4.599 180)
			(layer "B.Fab")
			(effects
				(font
					(size 0.7 0.7)
					(thickness 0.15)
				)
				(justify left bottom mirror)
			)
		)
		(pad "1" smd roundrect
			(at -0.48 0)
			(size 0.59 0.64)
			(layers "B.Cu" "B.Mask" "B.Paste")
			(roundrect_rratio 0.25)
			(net 417 "GND")
			(pintype "passive")
		)
		(pad "2" smd roundrect
			(at 0.48 0)
			(size 0.59 0.64)
			(layers "B.Cu" "B.Mask" "B.Paste")
			(roundrect_rratio 0.25)
			(net 137 "SD_VDD")
			(pintype "passive")
		)
	)
)
